# T6G (Grand Teton) — schematic netlist excerpt (pin names and nets, part order shuffled) for the footprints in the layout excerpt that follows; sources: Cadence DE-HDL packaged netlist, KiCad conversion of 04192023_DAF0TMB3IC0_F0TG_MB_C_brd_V02_OCP.brd

C2521  Q_CAP  22UF 4V 20% X6S  pkg C0402  page 71 : A = PVDD18_S5_P0 ; B = GND
C2554  Q_CAP  22UF 4V 20% X6S  pkg C0402  page 70 : A = PVDDCR_SOC_P0 ; B = GND
R840  Q_RES  1K 1% CHIP  pkg 0201LF  page 185 : A = P1V8_CPU0_RT_1D ; B = SMB_RT_CPU0_P2_ROM_R_SDA

(kicad_pcb
	(version 20260206)
	(generator "pcbnew")
	(generator_version "10.0")
	(general
		(thickness 1.6)
		(legacy_teardrops no)
	)
	(paper "A4")
	(title_block
		(title "04192023_DAF0TMB3IC0_F0TG_MB_C_brd_V02_OCP.brd")
		(comment 1 "Grand Teton / footprints 7373-7375 of 8354")
	)
	(layers
		(0 "F.Cu" signal "TOP")
		(4 "In1.Cu" signal "GND")
		(6 "In2.Cu" signal "IN1")
		(8 "In3.Cu" signal "GND1")
		(10 "In4.Cu" signal "IN2")
		(12 "In5.Cu" signal "GND2")
		(14 "In6.Cu" signal "IN3")
		(16 "In7.Cu" signal "GND3")
		(18 "In8.Cu" signal "VCC")
		(20 "In9.Cu" signal "VCC1")
		(22 "In10.Cu" signal "GND4")
		(24 "In11.Cu" signal "IN4")
		(26 "In12.Cu" signal "GND5")
		(28 "In13.Cu" signal "IN5")
		(30 "In14.Cu" signal "GND6")
		(32 "In15.Cu" signal "IN6")
		(34 "In16.Cu" signal "GND7")
		(2 "B.Cu" signal "BOTTOM")
		(9 "F.Adhes" user "F.Adhesive")
		(11 "B.Adhes" user "B.Adhesive")
		(13 "F.Paste" user "Package Geometry/Pastemask Top")
		(15 "B.Paste" user "Package Geometry/Pastemask Bottom")
		(5 "F.SilkS" user "Ref Des/Silkscreen Top")
		(7 "B.SilkS" user "Ref Des/Silkscreen Bottom")
		(1 "F.Mask" user "Board Geometry/Soldermask Top")
		(3 "B.Mask" user "Board Geometry/Soldermask Bottom")
		(17 "Dwgs.User" user "User.Drawings")
		(19 "Cmts.User" user "User.Comments")
		(21 "Eco1.User" user "User.Eco1")
		(23 "Eco2.User" user "User.Eco2")
		(25 "Edge.Cuts" user "Board Geometry/Outline")
		(27 "Margin" user)
		(31 "F.CrtYd" user "Package Geometry/Place Bound Top")
		(29 "B.CrtYd" user "Package Geometry/Place Bound Bottom")
		(35 "F.Fab" user "Ref Des/Assembly Top")
		(33 "B.Fab" user "Ref Des/Assembly Bottom")
	)
	(footprint ""
		(layer "B.Cu")
		(at 347.008958 -250.89231 180)
		(property "Reference" "C2521"
			(at 0 0 0)
			(layer "B.SilkS")
			(hide yes)
			(effects
				(font
					(size 1.27 1.27)
				)
				(justify mirror)
			)
		)
		(property "Value" ""
			(at 0 0 0)
			(layer "B.Fab")
			(effects
				(font
					(size 1.27 1.27)
				)
				(justify mirror)
			)
		)
		(duplicate_pad_numbers_are_jumpers no)
		(fp_line
			(start 0.7874 0.4064)
			(end 0.7874 -0.4064)
			(stroke
				(width 0.1524)
				(type default)
			)
			(layer "B.SilkS")
		)
		(fp_line
			(start 0.7874 -0.4064)
			(end -0.7874 -0.4064)
			(stroke
				(width 0.1524)
				(type default)
			)
			(layer "B.SilkS")
		)
		(fp_line
			(start -0.7874 0.4064)
			(end 0.7874 0.4064)
			(stroke
				(width 0.1524)
				(type default)
			)
			(layer "B.SilkS")
		)
		(fp_line
			(start -0.7874 -0.4064)
			(end -0.7874 0.4064)
			(stroke
				(width 0.1524)
				(type default)
			)
			(layer "B.SilkS")
		)
		(fp_line
			(start 0.67945 0.3048)
			(end 0.67945 -0.305054)
			(stroke
				(width 0.1)
				(type default)
			)
			(layer "B.Fab")
		)
		(fp_line
			(start 0.67945 -0.305054)
			(end 0.12065 -0.305054)
			(stroke
				(width 0.1)
				(type default)
			)
			(layer "B.Fab")
		)
		(fp_line
			(start 0.12065 0.3048)
			(end 0.67945 0.3048)
			(stroke
				(width 0.1)
				(type default)
			)
			(layer "B.Fab")
		)
		(fp_line
			(start 0.12065 0.2794)
			(end 0.12065 0.3048)
			(stroke
				(width 0.1)
				(type default)
			)
			(layer "B.Fab")
		)
		(fp_line
			(start 0.12065 -0.2794)
			(end -0.12065 -0.2794)
			(stroke
				(width 0.1)
				(type default)
			)
			(layer "B.Fab")
		)
		(fp_line
			(start 0.12065 -0.305054)
			(end 0.12065 -0.2794)
			(stroke
				(width 0.1)
				(type default)
			)
			(layer "B.Fab")
		)
		(fp_line
			(start -0.120396 0.3048)
			(end -0.120396 0.2794)
			(stroke
				(width 0.1)
				(type default)
			)
			(layer "B.Fab")
		)
		(fp_line
			(start -0.120396 0.2794)
			(end 0.12065 0.2794)
			(stroke
				(width 0.1)
				(type default)
			)
			(layer "B.Fab")
		)
		(fp_line
			(start -0.12065 -0.2794)
			(end -0.12065 -0.3048)
			(stroke
				(width 0.1)
				(type default)
			)
			(layer "B.Fab")
		)
		(fp_line
			(start -0.12065 -0.3048)
			(end -0.67945 -0.3048)
			(stroke
				(width 0.1)
				(type default)
			)
			(layer "B.Fab")
		)
		(fp_line
			(start -0.67945 0.3048)
			(end -0.120396 0.3048)
			(stroke
				(width 0.1)
				(type default)
			)
			(layer "B.Fab")
		)
		(fp_line
			(start -0.67945 -0.3048)
			(end -0.67945 0.3048)
			(stroke
				(width 0.1)
				(type default)
			)
			(layer "B.Fab")
		)
		(pad "1" smd circle
			(at 0.40005 0)
			(size 0 0)
			(layers "B.Cu" "B.Mask" "B.Paste")
			(net "PVDD18_S5_P0")
		)
		(pad "2" smd circle
			(at -0.40005 0)
			(size 0 0)
			(layers "B.Cu" "B.Mask" "B.Paste")
			(net "GND")
		)
	)
	(footprint ""
		(layer "B.Cu")
		(at 419.129464 -426.799248 180)
		(property "Reference" "R840"
			(at 0 0 0)
			(layer "B.SilkS")
			(hide yes)
			(effects
				(font
					(size 1.27 1.27)
				)
				(justify mirror)
			)
		)
		(property "Value" ""
			(at 0 0 0)
			(layer "B.Fab")
			(effects
				(font
					(size 1.27 1.27)
				)
				(justify mirror)
			)
		)
		(duplicate_pad_numbers_are_jumpers no)
		(fp_line
			(start 0.32512 0.175006)
			(end 0.32512 -0.175006)
			(stroke
				(width 0.1)
				(type default)
			)
			(layer "B.Fab")
		)
		(fp_line
			(start 0.32512 -0.175006)
			(end -0.32512 -0.175006)
			(stroke
				(width 0.1)
				(type default)
			)
			(layer "B.Fab")
		)
		(fp_line
			(start -0.32512 0.175006)
			(end 0.32512 0.175006)
			(stroke
				(width 0.1)
				(type default)
			)
			(layer "B.Fab")
		)
		(fp_line
			(start -0.32512 -0.175006)
			(end -0.32512 0.175006)
			(stroke
				(width 0.1)
				(type default)
			)
			(layer "B.Fab")
		)
		(pad "1" smd rect
			(at 0.2667 0)
			(size 0.3048 0.381)
			(layers "B.Cu" "B.Mask" "B.Paste")
			(net "P1V8_CPU0_RT_1D")
		)
		(pad "2" smd rect
			(at -0.2667 0 180)
			(size 0.3048 0.381)
			(layers "B.Cu" "B.Mask" "B.Paste")
			(net "SMB_RT_CPU0_P2_ROM_R_SDA")
		)
	)
	(footprint ""
		(layer "B.Cu")
		(at 350.342454 -256.73431 180)
		(property "Reference" "C2554"
			(at 0 0 0)
			(layer "B.SilkS")
			(hide yes)
			(effects
				(font
					(size 1.27 1.27)
				)
				(justify mirror)
			)
		)
		(property "Value" ""
			(at 0 0 0)
			(layer "B.Fab")
			(effects
				(font
					(size 1.27 1.27)
				)
				(justify mirror)
			)
		)
		(duplicate_pad_numbers_are_jumpers no)
		(fp_line
			(start 0.7874 0.4064)
			(end 0.7874 -0.4064)
			(stroke
				(width 0.1524)
				(type default)
			)
			(layer "B.SilkS")
		)
		(fp_line
			(start 0.7874 -0.4064)
			(end -0.7874 -0.4064)
			(stroke
				(width 0.1524)
				(type default)
			)
			(layer "B.SilkS")
		)
		(fp_line
			(start -0.7874 0.4064)
			(end 0.7874 0.4064)
			(stroke
				(width 0.1524)
				(type default)
			)
			(layer "B.SilkS")
		)
		(fp_line
			(start -0.7874 -0.4064)
			(end -0.7874 0.4064)
			(stroke
				(width 0.1524)
				(type default)
			)
			(layer "B.SilkS")
		)
		(fp_line
			(start 0.67945 0.3048)
			(end 0.67945 -0.305054)
			(stroke
				(width 0.1)
				(type default)
			)
			(layer "B.Fab")
		)
		(fp_line
			(start 0.67945 -0.305054)
			(end 0.12065 -0.305054)
			(stroke
				(width 0.1)
				(type default)
			)
			(layer "B.Fab")
		)
		(fp_line
			(start 0.12065 0.3048)
			(end 0.67945 0.3048)
			(stroke
				(width 0.1)
				(type default)
			)
			(layer "B.Fab")
		)
		(fp_line
			(start 0.12065 0.2794)
			(end 0.12065 0.3048)
			(stroke
				(width 0.1)
				(type default)
			)
			(layer "B.Fab")
		)
		(fp_line
			(start 0.12065 -0.2794)
			(end -0.12065 -0.2794)
			(stroke
				(width 0.1)
				(type default)
			)
			(layer "B.Fab")
		)
		(fp_line
			(start 0.12065 -0.305054)
			(end 0.12065 -0.2794)
			(stroke
				(width 0.1)
				(type default)
			)
			(layer "B.Fab")
		)
		(fp_line
			(start -0.120396 0.3048)
			(end -0.120396 0.2794)
			(stroke
				(width 0.1)
				(type default)
			)
			(layer "B.Fab")
		)
		(fp_line
			(start -0.120396 0.2794)
			(end 0.12065 0.2794)
			(stroke
				(width 0.1)
				(type default)
			)
			(layer "B.Fab")
		)
		(fp_line
			(start -0.12065 -0.2794)
			(end -0.12065 -0.3048)
			(stroke
				(width 0.1)
				(type default)
			)
			(layer "B.Fab")
		)
		(fp_line
			(start -0.12065 -0.3048)
			(end -0.67945 -0.3048)
			(stroke
				(width 0.1)
				(type default)
			)
			(layer "B.Fab")
		)
		(fp_line
			(start -0.67945 0.3048)
			(end -0.120396 0.3048)
			(stroke
				(width 0.1)
				(type default)
			)
			(layer "B.Fab")
		)
		(fp_line
			(start -0.67945 -0.3048)
			(end -0.67945 0.3048)
			(stroke
				(width 0.1)
				(type default)
			)
			(layer "B.Fab")
		)
		(pad "1" smd circle
			(at 0.40005 0)
			(size 0 0)
			(layers "B.Cu" "B.Mask" "B.Paste")
			(net "PVDDCR_SOC_P0")
		)
		(pad "2" smd circle
			(at -0.40005 0)
			(size 0 0)
			(layers "B.Cu" "B.Mask" "B.Paste")
			(net "GND")
		)
	)
)
